# T6G (Grand Teton) — schematic netlist excerpt (pin names and nets, part order shuffled) for the footprints in the layout excerpt that follows; sources: Cadence DE-HDL packaged netlist, KiCad conversion of 04192023_DAF0TMB3IC0_F0TG_MB_C_brd_V02_OCP.brd

R4183  Q_RES  33.2 1% CHIP  pkg 0402LF  page 235 : A = SMB_LM75_0_3V3AUX_SDA ; B = SMB_LM75_0_3V3AUX_SDA_R1
R662  Q_RES  0 5% CHIP  pkg 0402LF  page 364 : A = P0V9_RETIMER_CPU1_EN ; B = P0V9_RETIMER_CPU1_EN0_R

(kicad_pcb
	(version 20260206)
	(generator "pcbnew")
	(generator_version "10.0")
	(general
		(thickness 1.6)
		(legacy_teardrops no)
	)
	(paper "A4")
	(title_block
		(title "04192023_DAF0TMB3IC0_F0TG_MB_C_brd_V02_OCP.brd")
		(comment 1 "Grand Teton / footprints 1792-1793 of 8354")
	)
	(layers
		(0 "F.Cu" signal "TOP")
		(4 "In1.Cu" signal "GND")
		(6 "In2.Cu" signal "IN1")
		(8 "In3.Cu" signal "GND1")
		(10 "In4.Cu" signal "IN2")
		(12 "In5.Cu" signal "GND2")
		(14 "In6.Cu" signal "IN3")
		(16 "In7.Cu" signal "GND3")
		(18 "In8.Cu" signal "VCC")
		(20 "In9.Cu" signal "VCC1")
		(22 "In10.Cu" signal "GND4")
		(24 "In11.Cu" signal "IN4")
		(26 "In12.Cu" signal "GND5")
		(28 "In13.Cu" signal "IN5")
		(30 "In14.Cu" signal "GND6")
		(32 "In15.Cu" signal "IN6")
		(34 "In16.Cu" signal "GND7")
		(2 "B.Cu" signal "BOTTOM")
		(9 "F.Adhes" user "F.Adhesive")
		(11 "B.Adhes" user "B.Adhesive")
		(13 "F.Paste" user "Package Geometry/Pastemask Top")
		(15 "B.Paste" user "Package Geometry/Pastemask Bottom")
		(5 "F.SilkS" user "Ref Des/Silkscreen Top")
		(7 "B.SilkS" user "Ref Des/Silkscreen Bottom")
		(1 "F.Mask" user "Board Geometry/Soldermask Top")
		(3 "B.Mask" user "Board Geometry/Soldermask Bottom")
		(17 "Dwgs.User" user "User.Drawings")
		(19 "Cmts.User" user "User.Comments")
		(21 "Eco1.User" user "User.Eco1")
		(23 "Eco2.User" user "User.Eco2")
		(25 "Edge.Cuts" user "Board Geometry/Outline")
		(27 "Margin" user)
		(31 "F.CrtYd" user "Package Geometry/Place Bound Top")
		(29 "B.CrtYd" user "Package Geometry/Place Bound Bottom")
		(35 "F.Fab" user "Ref Des/Assembly Top")
		(33 "B.Fab" user "Ref Des/Assembly Bottom")
	)
	(footprint ""
		(layer "F.Cu")
		(at 365.887 -413.639 90)
		(property "Reference" "R4183"
			(at 0 0 90)
			(layer "F.SilkS")
			(hide yes)
			(effects
				(font
					(size 1.27 1.27)
				)
			)
		)
		(property "Value" ""
			(at 0 0 90)
			(layer "F.Fab")
			(effects
				(font
					(size 1.27 1.27)
				)
			)
		)
		(duplicate_pad_numbers_are_jumpers no)
		(fp_line
			(start 0.7874 -0.4064)
			(end 0.7874 0.4064)
			(stroke
				(width 0.1524)
				(type default)
			)
			(layer "F.SilkS")
		)
		(fp_line
			(start -0.7874 -0.4064)
			(end 0.7874 -0.4064)
			(stroke
				(width 0.1524)
				(type default)
			)
			(layer "F.SilkS")
		)
		(fp_line
			(start 0.7874 0.4064)
			(end -0.7874 0.4064)
			(stroke
				(width 0.1524)
				(type default)
			)
			(layer "F.SilkS")
		)
		(fp_line
			(start -0.7874 0.4064)
			(end -0.7874 -0.4064)
			(stroke
				(width 0.1524)
				(type default)
			)
			(layer "F.SilkS")
		)
		(fp_line
			(start -0.12065 -0.305054)
			(end -0.12065 -0.2794)
			(stroke
				(width 0.1)
				(type default)
			)
			(layer "F.Fab")
		)
		(fp_line
			(start -0.67945 -0.305054)
			(end -0.12065 -0.305054)
			(stroke
				(width 0.1)
				(type default)
			)
			(layer "F.Fab")
		)
		(fp_line
			(start 0.67945 -0.3048)
			(end 0.67945 0.3048)
			(stroke
				(width 0.1)
				(type default)
			)
			(layer "F.Fab")
		)
		(fp_line
			(start 0.12065 -0.3048)
			(end 0.67945 -0.3048)
			(stroke
				(width 0.1)
				(type default)
			)
			(layer "F.Fab")
		)
		(fp_line
			(start 0.12065 -0.2794)
			(end 0.12065 -0.3048)
			(stroke
				(width 0.1)
				(type default)
			)
			(layer "F.Fab")
		)
		(fp_line
			(start -0.12065 -0.2794)
			(end 0.12065 -0.2794)
			(stroke
				(width 0.1)
				(type default)
			)
			(layer "F.Fab")
		)
		(fp_line
			(start 0.120396 0.2794)
			(end -0.12065 0.2794)
			(stroke
				(width 0.1)
				(type default)
			)
			(layer "F.Fab")
		)
		(fp_line
			(start -0.12065 0.2794)
			(end -0.12065 0.3048)
			(stroke
				(width 0.1)
				(type default)
			)
			(layer "F.Fab")
		)
		(fp_line
			(start 0.67945 0.3048)
			(end 0.120396 0.3048)
			(stroke
				(width 0.1)
				(type default)
			)
			(layer "F.Fab")
		)
		(fp_line
			(start 0.120396 0.3048)
			(end 0.120396 0.2794)
			(stroke
				(width 0.1)
				(type default)
			)
			(layer "F.Fab")
		)
		(fp_line
			(start -0.12065 0.3048)
			(end -0.67945 0.3048)
			(stroke
				(width 0.1)
				(type default)
			)
			(layer "F.Fab")
		)
		(fp_line
			(start -0.67945 0.3048)
			(end -0.67945 -0.305054)
			(stroke
				(width 0.1)
				(type default)
			)
			(layer "F.Fab")
		)
		(pad "1" smd circle
			(at -0.40005 0 90)
			(size 0 0)
			(layers "F.Cu" "F.Mask" "F.Paste")
			(net "SMB_LM75_0_3V3AUX_SDA")
		)
		(pad "2" smd circle
			(at 0.40005 0 90)
			(size 0 0)
			(layers "F.Cu" "F.Mask" "F.Paste")
			(net "SMB_LM75_0_3V3AUX_SDA_R1")
		)
	)
	(footprint ""
		(layer "F.Cu")
		(at 20.981924 -407.976578 90)
		(property "Reference" "R662"
			(at 0 0 90)
			(layer "F.SilkS")
			(hide yes)
			(effects
				(font
					(size 1.27 1.27)
				)
			)
		)
		(property "Value" ""
			(at 0 0 90)
			(layer "F.Fab")
			(effects
				(font
					(size 1.27 1.27)
				)
			)
		)
		(duplicate_pad_numbers_are_jumpers no)
		(fp_line
			(start 0.7874 -0.4064)
			(end 0.7874 0.4064)
			(stroke
				(width 0.1524)
				(type default)
			)
			(layer "F.SilkS")
		)
		(fp_line
			(start -0.7874 -0.4064)
			(end 0.7874 -0.4064)
			(stroke
				(width 0.1524)
				(type default)
			)
			(layer "F.SilkS")
		)
		(fp_line
			(start 0.7874 0.4064)
			(end -0.7874 0.4064)
			(stroke
				(width 0.1524)
				(type default)
			)
			(layer "F.SilkS")
		)
		(fp_line
			(start -0.7874 0.4064)
			(end -0.7874 -0.4064)
			(stroke
				(width 0.1524)
				(type default)
			)
			(layer "F.SilkS")
		)
		(fp_line
			(start -0.12065 -0.305054)
			(end -0.12065 -0.2794)
			(stroke
				(width 0.1)
				(type default)
			)
			(layer "F.Fab")
		)
		(fp_line
			(start -0.67945 -0.305054)
			(end -0.12065 -0.305054)
			(stroke
				(width 0.1)
				(type default)
			)
			(layer "F.Fab")
		)
		(fp_line
			(start 0.67945 -0.3048)
			(end 0.67945 0.3048)
			(stroke
				(width 0.1)
				(type default)
			)
			(layer "F.Fab")
		)
		(fp_line
			(start 0.12065 -0.3048)
			(end 0.67945 -0.3048)
			(stroke
				(width 0.1)
				(type default)
			)
			(layer "F.Fab")
		)
		(fp_line
			(start 0.12065 -0.2794)
			(end 0.12065 -0.3048)
			(stroke
				(width 0.1)
				(type default)
			)
			(layer "F.Fab")
		)
		(fp_line
			(start -0.12065 -0.2794)
			(end 0.12065 -0.2794)
			(stroke
				(width 0.1)
				(type default)
			)
			(layer "F.Fab")
		)
		(fp_line
			(start 0.120396 0.2794)
			(end -0.12065 0.2794)
			(stroke
				(width 0.1)
				(type default)
			)
			(layer "F.Fab")
		)
		(fp_line
			(start -0.12065 0.2794)
			(end -0.12065 0.3048)
			(stroke
				(width 0.1)
				(type default)
			)
			(layer "F.Fab")
		)
		(fp_line
			(start 0.67945 0.3048)
			(end 0.120396 0.3048)
			(stroke
				(width 0.1)
				(type default)
			)
			(layer "F.Fab")
		)
		(fp_line
			(start 0.120396 0.3048)
			(end 0.120396 0.2794)
			(stroke
				(width 0.1)
				(type default)
			)
			(layer "F.Fab")
		)
		(fp_line
			(start -0.12065 0.3048)
			(end -0.67945 0.3048)
			(stroke
				(width 0.1)
				(type default)
			)
			(layer "F.Fab")
		)
		(fp_line
			(start -0.67945 0.3048)
			(end -0.67945 -0.305054)
			(stroke
				(width 0.1)
				(type default)
			)
			(layer "F.Fab")
		)
		(pad "1" smd circle
			(at -0.40005 0 90)
			(size 0 0)
			(layers "F.Cu" "F.Mask" "F.Paste")
			(net "P0V9_RETIMER_CPU1_EN")
		)
		(pad "2" smd circle
			(at 0.40005 0 90)
			(size 0 0)
			(layers "F.Cu" "F.Mask" "F.Paste")
			(net "P0V9_RETIMER_CPU1_EN0_R")
		)
	)
)
